# T6G (Grand Teton) — schematic netlist excerpt (pin names and nets, part order shuffled) for the footprints in the layout excerpt that follows; sources: Cadence DE-HDL packaged netlist, KiCad conversion of 04192023_DAF0TMB3IC0_F0TG_MB_C_brd_V02_OCP.brd

PR284  Q_RES  1K 1% EMPTY  pkg 0402LF  page 193 : A = PVDD18_S5_P0 ; B = SVID_PVDDCR_CPU0_P0_SVTI
PC138  Q_CAP  2.2UF 10V 10% X6S  pkg C0402  page 220 : A = PVDDCR_CPU1_P1_VCC6 ; B = GND

(kicad_pcb
	(version 20260206)
	(generator "pcbnew")
	(generator_version "10.0")
	(general
		(thickness 1.6)
		(legacy_teardrops no)
	)
	(paper "A4")
	(title_block
		(title "04192023_DAF0TMB3IC0_F0TG_MB_C_brd_V02_OCP.brd")
		(comment 1 "Grand Teton / footprints 336-337 of 8354")
	)
	(layers
		(0 "F.Cu" signal "TOP")
		(4 "In1.Cu" signal "GND")
		(6 "In2.Cu" signal "IN1")
		(8 "In3.Cu" signal "GND1")
		(10 "In4.Cu" signal "IN2")
		(12 "In5.Cu" signal "GND2")
		(14 "In6.Cu" signal "IN3")
		(16 "In7.Cu" signal "GND3")
		(18 "In8.Cu" signal "VCC")
		(20 "In9.Cu" signal "VCC1")
		(22 "In10.Cu" signal "GND4")
		(24 "In11.Cu" signal "IN4")
		(26 "In12.Cu" signal "GND5")
		(28 "In13.Cu" signal "IN5")
		(30 "In14.Cu" signal "GND6")
		(32 "In15.Cu" signal "IN6")
		(34 "In16.Cu" signal "GND7")
		(2 "B.Cu" signal "BOTTOM")
		(9 "F.Adhes" user "F.Adhesive")
		(11 "B.Adhes" user "B.Adhesive")
		(13 "F.Paste" user "Package Geometry/Pastemask Top")
		(15 "B.Paste" user "Package Geometry/Pastemask Bottom")
		(5 "F.SilkS" user "Ref Des/Silkscreen Top")
		(7 "B.SilkS" user "Ref Des/Silkscreen Bottom")
		(1 "F.Mask" user "Board Geometry/Soldermask Top")
		(3 "B.Mask" user "Board Geometry/Soldermask Bottom")
		(17 "Dwgs.User" user "User.Drawings")
		(19 "Cmts.User" user "User.Comments")
		(21 "Eco1.User" user "User.Eco1")
		(23 "Eco2.User" user "User.Eco2")
		(25 "Edge.Cuts" user "Board Geometry/Outline")
		(27 "Margin" user)
		(31 "F.CrtYd" user "Package Geometry/Place Bound Top")
		(29 "B.CrtYd" user "Package Geometry/Place Bound Bottom")
		(35 "F.Fab" user "Ref Des/Assembly Top")
		(33 "B.Fab" user "Ref Des/Assembly Bottom")
	)
	(footprint ""
		(layer "F.Cu")
		(at 100.046282 -342.604598 90)
		(property "Reference" "PC138"
			(at 0 0 90)
			(layer "F.SilkS")
			(hide yes)
			(effects
				(font
					(size 1.27 1.27)
				)
			)
		)
		(property "Value" ""
			(at 0 0 90)
			(layer "F.Fab")
			(effects
				(font
					(size 1.27 1.27)
				)
			)
		)
		(duplicate_pad_numbers_are_jumpers no)
		(fp_line
			(start 0.7874 -0.4064)
			(end 0.7874 0.4064)
			(stroke
				(width 0.1524)
				(type default)
			)
			(layer "F.SilkS")
		)
		(fp_line
			(start -0.7874 -0.4064)
			(end 0.7874 -0.4064)
			(stroke
				(width 0.1524)
				(type default)
			)
			(layer "F.SilkS")
		)
		(fp_line
			(start 0.7874 0.4064)
			(end 0.371602 0.4064)
			(stroke
				(width 0.1524)
				(type default)
			)
			(layer "F.SilkS")
		)
		(fp_line
			(start -0.263398 0.4064)
			(end -0.7874 0.4064)
			(stroke
				(width 0.1524)
				(type default)
			)
			(layer "F.SilkS")
		)
		(fp_line
			(start -0.7874 0.4064)
			(end -0.7874 -0.4064)
			(stroke
				(width 0.1524)
				(type default)
			)
			(layer "F.SilkS")
		)
		(fp_line
			(start -0.12065 -0.305054)
			(end -0.12065 -0.2794)
			(stroke
				(width 0.1)
				(type default)
			)
			(layer "F.Fab")
		)
		(fp_line
			(start -0.67945 -0.305054)
			(end -0.12065 -0.305054)
			(stroke
				(width 0.1)
				(type default)
			)
			(layer "F.Fab")
		)
		(fp_line
			(start 0.67945 -0.3048)
			(end 0.67945 0.3048)
			(stroke
				(width 0.1)
				(type default)
			)
			(layer "F.Fab")
		)
		(fp_line
			(start 0.12065 -0.3048)
			(end 0.67945 -0.3048)
			(stroke
				(width 0.1)
				(type default)
			)
			(layer "F.Fab")
		)
		(fp_line
			(start 0.12065 -0.2794)
			(end 0.12065 -0.3048)
			(stroke
				(width 0.1)
				(type default)
			)
			(layer "F.Fab")
		)
		(fp_line
			(start -0.12065 -0.2794)
			(end 0.12065 -0.2794)
			(stroke
				(width 0.1)
				(type default)
			)
			(layer "F.Fab")
		)
		(fp_line
			(start 0.120396 0.2794)
			(end -0.12065 0.2794)
			(stroke
				(width 0.1)
				(type default)
			)
			(layer "F.Fab")
		)
		(fp_line
			(start -0.12065 0.2794)
			(end -0.12065 0.3048)
			(stroke
				(width 0.1)
				(type default)
			)
			(layer "F.Fab")
		)
		(fp_line
			(start 0.67945 0.3048)
			(end 0.120396 0.3048)
			(stroke
				(width 0.1)
				(type default)
			)
			(layer "F.Fab")
		)
		(fp_line
			(start 0.120396 0.3048)
			(end 0.120396 0.2794)
			(stroke
				(width 0.1)
				(type default)
			)
			(layer "F.Fab")
		)
		(fp_line
			(start -0.12065 0.3048)
			(end -0.67945 0.3048)
			(stroke
				(width 0.1)
				(type default)
			)
			(layer "F.Fab")
		)
		(fp_line
			(start -0.67945 0.3048)
			(end -0.67945 -0.305054)
			(stroke
				(width 0.1)
				(type default)
			)
			(layer "F.Fab")
		)
		(pad "1" smd circle
			(at -0.40005 0 90)
			(size 0 0)
			(layers "F.Cu" "F.Mask" "F.Paste")
			(net "PVDDCR_CPU1_P1_VCC6")
		)
		(pad "2" smd circle
			(at 0.40005 0 90)
			(size 0 0)
			(layers "F.Cu" "F.Mask" "F.Paste")
			(net "GND")
		)
	)
	(footprint ""
		(layer "F.Cu")
		(at 372.937278 -147.568158 180)
		(property "Reference" "PR284"
			(at 0 0 180)
			(layer "F.SilkS")
			(hide yes)
			(effects
				(font
					(size 1.27 1.27)
				)
			)
		)
		(property "Value" ""
			(at 0 0 180)
			(layer "F.Fab")
			(effects
				(font
					(size 1.27 1.27)
				)
			)
		)
		(duplicate_pad_numbers_are_jumpers no)
		(fp_line
			(start 0.7874 0.4064)
			(end -0.7874 0.4064)
			(stroke
				(width 0.1524)
				(type default)
			)
			(layer "F.SilkS")
		)
		(fp_line
			(start 0.7874 -0.4064)
			(end 0.7874 0.4064)
			(stroke
				(width 0.1524)
				(type default)
			)
			(layer "F.SilkS")
		)
		(fp_line
			(start -0.7874 0.4064)
			(end -0.7874 -0.4064)
			(stroke
				(width 0.1524)
				(type default)
			)
			(layer "F.SilkS")
		)
		(fp_line
			(start -0.7874 -0.4064)
			(end 0.7874 -0.4064)
			(stroke
				(width 0.1524)
				(type default)
			)
			(layer "F.SilkS")
		)
		(fp_line
			(start 0.67945 0.3048)
			(end 0.120396 0.3048)
			(stroke
				(width 0.1)
				(type default)
			)
			(layer "F.Fab")
		)
		(fp_line
			(start 0.67945 -0.3048)
			(end 0.67945 0.3048)
			(stroke
				(width 0.1)
				(type default)
			)
			(layer "F.Fab")
		)
		(fp_line
			(start 0.12065 -0.2794)
			(end 0.12065 -0.3048)
			(stroke
				(width 0.1)
				(type default)
			)
			(layer "F.Fab")
		)
		(fp_line
			(start 0.12065 -0.3048)
			(end 0.67945 -0.3048)
			(stroke
				(width 0.1)
				(type default)
			)
			(layer "F.Fab")
		)
		(fp_line
			(start 0.120396 0.3048)
			(end 0.120396 0.2794)
			(stroke
				(width 0.1)
				(type default)
			)
			(layer "F.Fab")
		)
		(fp_line
			(start 0.120396 0.2794)
			(end -0.12065 0.2794)
			(stroke
				(width 0.1)
				(type default)
			)
			(layer "F.Fab")
		)
		(fp_line
			(start -0.12065 0.3048)
			(end -0.67945 0.3048)
			(stroke
				(width 0.1)
				(type default)
			)
			(layer "F.Fab")
		)
		(fp_line
			(start -0.12065 0.2794)
			(end -0.12065 0.3048)
			(stroke
				(width 0.1)
				(type default)
			)
			(layer "F.Fab")
		)
		(fp_line
			(start -0.12065 -0.2794)
			(end 0.12065 -0.2794)
			(stroke
				(width 0.1)
				(type default)
			)
			(layer "F.Fab")
		)
		(fp_line
			(start -0.12065 -0.305054)
			(end -0.12065 -0.2794)
			(stroke
				(width 0.1)
				(type default)
			)
			(layer "F.Fab")
		)
		(fp_line
			(start -0.67945 0.3048)
			(end -0.67945 -0.305054)
			(stroke
				(width 0.1)
				(type default)
			)
			(layer "F.Fab")
		)
		(fp_line
			(start -0.67945 -0.305054)
			(end -0.12065 -0.305054)
			(stroke
				(width 0.1)
				(type default)
			)
			(layer "F.Fab")
		)
		(pad "1" smd circle
			(at -0.40005 0 180)
			(size 0 0)
			(layers "F.Cu" "F.Mask" "F.Paste")
			(net "PVDD18_S5_P0")
		)
		(pad "2" smd circle
			(at 0.40005 0 180)
			(size 0 0)
			(layers "F.Cu" "F.Mask" "F.Paste")
			(net "SVID_PVDDCR_CPU0_P0_SVTI")
		)
	)
)
